# T6G (Grand Teton) — schematic netlist excerpt (pin names and nets, part order shuffled) for the footprints in the layout excerpt that follows; sources: Cadence DE-HDL packaged netlist, KiCad conversion of 04192023_DAF0TMB3IC0_F0TG_MB_C_brd_V02_OCP.brd

C7031  Q_CAP  100UF 4V 20% X6S  pkg C0805  page 356 : A = P0V9_CPU1_RT3_2A ; B = GND
PC452  Q_CAPP  470UF 2.5V 20% SPCAP  pkg SMLF  page 222 : A = PVDDIO_P1 ; B = GND
C534  Q_CAP  10UF 25V 10% X6S  pkg C0805  page 106 : A = P12V_MEM_CPU1 ; B = GND

(kicad_pcb
	(version 20260206)
	(generator "pcbnew")
	(generator_version "10.0")
	(general
		(thickness 1.6)
		(legacy_teardrops no)
	)
	(paper "A4")
	(title_block
		(title "04192023_DAF0TMB3IC0_F0TG_MB_C_brd_V02_OCP.brd")
		(comment 1 "Grand Teton / footprints 8029-8031 of 8354")
	)
	(layers
		(0 "F.Cu" signal "TOP")
		(4 "In1.Cu" signal "GND")
		(6 "In2.Cu" signal "IN1")
		(8 "In3.Cu" signal "GND1")
		(10 "In4.Cu" signal "IN2")
		(12 "In5.Cu" signal "GND2")
		(14 "In6.Cu" signal "IN3")
		(16 "In7.Cu" signal "GND3")
		(18 "In8.Cu" signal "VCC")
		(20 "In9.Cu" signal "VCC1")
		(22 "In10.Cu" signal "GND4")
		(24 "In11.Cu" signal "IN4")
		(26 "In12.Cu" signal "GND5")
		(28 "In13.Cu" signal "IN5")
		(30 "In14.Cu" signal "GND6")
		(32 "In15.Cu" signal "IN6")
		(34 "In16.Cu" signal "GND7")
		(2 "B.Cu" signal "BOTTOM")
		(9 "F.Adhes" user "F.Adhesive")
		(11 "B.Adhes" user "B.Adhesive")
		(13 "F.Paste" user "Package Geometry/Pastemask Top")
		(15 "B.Paste" user "Package Geometry/Pastemask Bottom")
		(5 "F.SilkS" user "Ref Des/Silkscreen Top")
		(7 "B.SilkS" user "Ref Des/Silkscreen Bottom")
		(1 "F.Mask" user "Board Geometry/Soldermask Top")
		(3 "B.Mask" user "Board Geometry/Soldermask Bottom")
		(17 "Dwgs.User" user "User.Drawings")
		(19 "Cmts.User" user "User.Comments")
		(21 "Eco1.User" user "User.Eco1")
		(23 "Eco2.User" user "User.Eco2")
		(25 "Edge.Cuts" user "Board Geometry/Outline")
		(27 "Margin" user)
		(31 "F.CrtYd" user "Package Geometry/Place Bound Top")
		(29 "B.CrtYd" user "Package Geometry/Place Bound Bottom")
		(35 "F.Fab" user "Ref Des/Assembly Top")
		(33 "B.Fab" user "Ref Des/Assembly Bottom")
	)
	(footprint ""
		(layer "B.Cu")
		(at 37.565076 -339.915754 -90)
		(property "Reference" "PC452"
			(at 9.447276 1.051814 270)
			(unlocked yes)
			(layer "B.SilkS")
			(effects
				(font
					(size 0.7874 0.5842)
					(thickness 0.1524)
				)
				(justify left mirror)
			)
		)
		(property "Value" ""
			(at 0 0 90)
			(layer "B.Fab")
			(effects
				(font
					(size 1.27 1.27)
				)
				(justify mirror)
			)
		)
		(duplicate_pad_numbers_are_jumpers no)
		(fp_line
			(start -4.533392 2.249932)
			(end 4.533392 2.249932)
			(stroke
				(width 0.1524)
				(type default)
			)
			(layer "B.SilkS")
		)
		(fp_line
			(start 4.533392 2.249932)
			(end 4.533392 -2.249932)
			(stroke
				(width 0.1524)
				(type default)
			)
			(layer "B.SilkS")
		)
		(fp_line
			(start -4.533392 -2.249932)
			(end -4.533392 2.249932)
			(stroke
				(width 0.1524)
				(type default)
			)
			(layer "B.SilkS")
		)
		(fp_line
			(start 4.533392 -2.249932)
			(end -4.533392 -2.249932)
			(stroke
				(width 0.1524)
				(type default)
			)
			(layer "B.SilkS")
		)
		(fp_rect
			(start 5.39242 2.326132)
			(end 4.533392 -2.326132)
			(stroke
				(width 0)
				(type default)
			)
			(fill yes)
			(layer "B.SilkS")
		)
		(fp_line
			(start -3.750056 2.249932)
			(end 3.750056 2.249932)
			(stroke
				(width 0.1)
				(type default)
			)
			(layer "B.Fab")
		)
		(fp_line
			(start 3.750056 2.249932)
			(end 3.750056 -2.249932)
			(stroke
				(width 0.1)
				(type default)
			)
			(layer "B.Fab")
		)
		(fp_line
			(start -3.750056 -2.249932)
			(end -3.750056 2.249932)
			(stroke
				(width 0.1)
				(type default)
			)
			(layer "B.Fab")
		)
		(fp_line
			(start 3.750056 -2.249932)
			(end -3.750056 -2.249932)
			(stroke
				(width 0.1)
				(type default)
			)
			(layer "B.Fab")
		)
		(fp_text user "+"
			(at 6.322314 0.786384 180)
			(unlocked yes)
			(layer "B.SilkS")
			(effects
				(font
					(size 1.905 1.4224)
					(thickness 0.1524)
				)
				(justify left mirror)
			)
		)
		(fp_text user "-"
			(at -4.27736 -1.846072 270)
			(unlocked yes)
			(layer "B.SilkS")
			(effects
				(font
					(size 1.905 1.4224)
					(thickness 0.1524)
				)
				(justify left mirror)
			)
		)
		(fp_text user "+"
			(at 6.322314 0.786384 180)
			(unlocked yes)
			(layer "B.Fab")
			(effects
				(font
					(size 1.905 1.4224)
					(thickness 0.1524)
				)
				(justify left mirror)
			)
		)
		(fp_text user "-"
			(at -4.8514 -0.14605 270)
			(unlocked yes)
			(layer "B.Fab")
			(effects
				(font
					(size 1.905 1.4224)
					(thickness 0.1524)
				)
				(justify left mirror)
			)
		)
		(pad "1" smd rect
			(at 3.199892 0 90)
			(size 2.413 2.8194)
			(layers "B.Cu" "B.Mask" "B.Paste")
			(net "PVDDIO_P1")
		)
		(pad "2" smd rect
			(at -3.199892 0 90)
			(size 2.413 2.8194)
			(layers "B.Cu" "B.Mask" "B.Paste")
			(net "GND")
		)
	)
	(footprint ""
		(layer "B.Cu")
		(at 112.624108 -381.321818)
		(property "Reference" "C7031"
			(at 0 0 0)
			(layer "B.SilkS")
			(hide yes)
			(effects
				(font
					(size 1.27 1.27)
				)
				(justify mirror)
			)
		)
		(property "Value" ""
			(at 0 0 0)
			(layer "B.Fab")
			(effects
				(font
					(size 1.27 1.27)
				)
				(justify mirror)
			)
		)
		(duplicate_pad_numbers_are_jumpers no)
		(fp_line
			(start -1.524 -0.762)
			(end -1.524 0.762)
			(stroke
				(width 0.1524)
				(type default)
			)
			(layer "B.SilkS")
		)
		(fp_line
			(start -1.524 0.762)
			(end 1.524 0.762)
			(stroke
				(width 0.1524)
				(type default)
			)
			(layer "B.SilkS")
		)
		(fp_line
			(start 1.524 -0.762)
			(end -1.524 -0.762)
			(stroke
				(width 0.1524)
				(type default)
			)
			(layer "B.SilkS")
		)
		(fp_line
			(start 1.524 0.762)
			(end 1.524 -0.762)
			(stroke
				(width 0.1524)
				(type default)
			)
			(layer "B.SilkS")
		)
		(fp_line
			(start -1.1049 -0.724916)
			(end 1.1049 -0.724916)
			(stroke
				(width 0.1)
				(type default)
			)
			(layer "B.Fab")
		)
		(fp_line
			(start -1.1049 0.724916)
			(end -1.1049 -0.724916)
			(stroke
				(width 0.1)
				(type default)
			)
			(layer "B.Fab")
		)
		(fp_line
			(start 1.1049 -0.724916)
			(end 1.1049 0.724916)
			(stroke
				(width 0.1)
				(type default)
			)
			(layer "B.Fab")
		)
		(fp_line
			(start 1.1049 0.724916)
			(end -1.1049 0.724916)
			(stroke
				(width 0.1)
				(type default)
			)
			(layer "B.Fab")
		)
		(pad "1" smd rect
			(at 0.889 0)
			(size 1.016 1.27)
			(layers "B.Cu" "B.Mask" "B.Paste")
			(net "P0V9_CPU1_RT3_2A")
		)
		(pad "2" smd rect
			(at -0.889 0)
			(size 1.016 1.27)
			(layers "B.Cu" "B.Mask" "B.Paste")
			(net "GND")
		)
	)
	(footprint ""
		(layer "B.Cu")
		(at 179.516278 -192.66027 180)
		(property "Reference" "C534"
			(at 0 0 0)
			(layer "B.SilkS")
			(hide yes)
			(effects
				(font
					(size 1.27 1.27)
				)
				(justify mirror)
			)
		)
		(property "Value" ""
			(at 0 0 0)
			(layer "B.Fab")
			(effects
				(font
					(size 1.27 1.27)
				)
				(justify mirror)
			)
		)
		(duplicate_pad_numbers_are_jumpers no)
		(fp_line
			(start 1.524 0.762)
			(end 1.524 -0.762)
			(stroke
				(width 0.1524)
				(type default)
			)
			(layer "B.SilkS")
		)
		(fp_line
			(start 1.524 -0.762)
			(end -1.524 -0.762)
			(stroke
				(width 0.1524)
				(type default)
			)
			(layer "B.SilkS")
		)
		(fp_line
			(start -1.524 0.762)
			(end 1.524 0.762)
			(stroke
				(width 0.1524)
				(type default)
			)
			(layer "B.SilkS")
		)
		(fp_line
			(start -1.524 -0.762)
			(end -1.524 0.762)
			(stroke
				(width 0.1524)
				(type default)
			)
			(layer "B.SilkS")
		)
		(fp_line
			(start 1.1049 0.724916)
			(end -1.1049 0.724916)
			(stroke
				(width 0.1)
				(type default)
			)
			(layer "B.Fab")
		)
		(fp_line
			(start 1.1049 -0.724916)
			(end 1.1049 0.724916)
			(stroke
				(width 0.1)
				(type default)
			)
			(layer "B.Fab")
		)
		(fp_line
			(start -1.1049 0.724916)
			(end -1.1049 -0.724916)
			(stroke
				(width 0.1)
				(type default)
			)
			(layer "B.Fab")
		)
		(fp_line
			(start -1.1049 -0.724916)
			(end 1.1049 -0.724916)
			(stroke
				(width 0.1)
				(type default)
			)
			(layer "B.Fab")
		)
		(pad "1" smd rect
			(at 0.889 0 180)
			(size 1.016 1.27)
			(layers "B.Cu" "B.Mask" "B.Paste")
			(net "P12V_MEM_CPU1")
		)
		(pad "2" smd rect
			(at -0.889 0 180)
			(size 1.016 1.27)
			(layers "B.Cu" "B.Mask" "B.Paste")
			(net "GND")
		)
	)
)
